# S9S_MB_2U (Grand Teton) — schematic netlist excerpt (pin names and nets, part order shuffled) for the footprints in the layout excerpt that follows; sources: Cadence DE-HDL packaged netlist, KiCad conversion of 03242023_DA0F0TMBIJ0_F0T_Motherboard_J_brd_V01_OCP.brd

R1545  Q_RES  2K 1% CHIP  pkg 0402LF  page 183 : A = SMB_SML0B_3V3AUX_SCL ; B = P3V3_AUX
R3477  Q_RES  33.2 1% CHIP  pkg 0402LF  page 213 : A = GPU_NVS_PWR_BRAKE_N ; B = GPU_NVS_PWR_BRAKE_R_N
C914  Q_CAP_DIFFBUS  DIFF BUS_0.22UF 6.3V 20% X6S  pkg C0201  page 173 : \1\ = P5E_CPU0_PE0_TX_C_DN<9> ; \2\ = P5E_CPU0_PE0_TX_DN<9>

(kicad_pcb
	(version 20260206)
	(generator "pcbnew")
	(generator_version "10.0")
	(general
		(thickness 1.6)
		(legacy_teardrops no)
	)
	(paper "A4")
	(title_block
		(title "03242023_DA0F0TMBIJ0_F0T_Motherboard_J_brd_V01_OCP.brd")
		(comment 1 "Grand Teton / footprints 128-130 of 6105")
	)
	(layers
		(0 "F.Cu" signal "TOP")
		(4 "In1.Cu" signal "GND")
		(6 "In2.Cu" signal "IN1")
		(8 "In3.Cu" signal "GND1")
		(10 "In4.Cu" signal "IN2")
		(12 "In5.Cu" signal "GND2")
		(14 "In6.Cu" signal "IN3")
		(16 "In7.Cu" signal "GND3")
		(18 "In8.Cu" signal "VCC")
		(20 "In9.Cu" signal "VCC1")
		(22 "In10.Cu" signal "GND4")
		(24 "In11.Cu" signal "IN4")
		(26 "In12.Cu" signal "GND5")
		(28 "In13.Cu" signal "IN5")
		(30 "In14.Cu" signal "GND6")
		(32 "In15.Cu" signal "IN6")
		(34 "In16.Cu" signal "GND7")
		(2 "B.Cu" signal "BOTTOM")
		(9 "F.Adhes" user "F.Adhesive")
		(11 "B.Adhes" user "B.Adhesive")
		(13 "F.Paste" user "Package Geometry/Pastemask Top")
		(15 "B.Paste" user "Package Geometry/Pastemask Bottom")
		(5 "F.SilkS" user "Ref Des/Silkscreen Top")
		(7 "B.SilkS" user "Ref Des/Silkscreen Bottom")
		(1 "F.Mask" user "Board Geometry/Soldermask Top")
		(3 "B.Mask" user "Board Geometry/Soldermask Bottom")
		(17 "Dwgs.User" user "User.Drawings")
		(19 "Cmts.User" user "User.Comments")
		(21 "Eco1.User" user "User.Eco1")
		(23 "Eco2.User" user "User.Eco2")
		(25 "Edge.Cuts" user "Board Geometry/Outline")
		(27 "Margin" user)
		(31 "F.CrtYd" user "Package Geometry/Place Bound Top")
		(29 "B.CrtYd" user "Package Geometry/Place Bound Bottom")
		(35 "F.Fab" user "Ref Des/Assembly Top")
		(33 "B.Fab" user "Ref Des/Assembly Bottom")
	)
	(footprint ""
		(layer "F.Cu")
		(at 313.53506 -26.062432 180)
		(property "Reference" "R1545"
			(at 0 0 180)
			(layer "F.SilkS")
			(hide yes)
			(effects
				(font
					(size 1.27 1.27)
				)
			)
		)
		(property "Value" ""
			(at 0 0 180)
			(layer "F.Fab")
			(effects
				(font
					(size 1.27 1.27)
				)
			)
		)
		(duplicate_pad_numbers_are_jumpers no)
		(fp_line
			(start 0.7874 0.4064)
			(end -0.7874 0.4064)
			(stroke
				(width 0.1524)
				(type default)
			)
			(layer "F.SilkS")
		)
		(fp_line
			(start 0.7874 -0.4064)
			(end 0.7874 0.4064)
			(stroke
				(width 0.1524)
				(type default)
			)
			(layer "F.SilkS")
		)
		(fp_line
			(start -0.7874 0.4064)
			(end -0.7874 -0.4064)
			(stroke
				(width 0.1524)
				(type default)
			)
			(layer "F.SilkS")
		)
		(fp_line
			(start -0.7874 -0.4064)
			(end 0.7874 -0.4064)
			(stroke
				(width 0.1524)
				(type default)
			)
			(layer "F.SilkS")
		)
		(fp_line
			(start 0.67945 0.3048)
			(end 0.120396 0.3048)
			(stroke
				(width 0.1)
				(type default)
			)
			(layer "F.Fab")
		)
		(fp_line
			(start 0.67945 -0.3048)
			(end 0.67945 0.3048)
			(stroke
				(width 0.1)
				(type default)
			)
			(layer "F.Fab")
		)
		(fp_line
			(start 0.12065 -0.2794)
			(end 0.12065 -0.3048)
			(stroke
				(width 0.1)
				(type default)
			)
			(layer "F.Fab")
		)
		(fp_line
			(start 0.12065 -0.3048)
			(end 0.67945 -0.3048)
			(stroke
				(width 0.1)
				(type default)
			)
			(layer "F.Fab")
		)
		(fp_line
			(start 0.120396 0.3048)
			(end 0.120396 0.2794)
			(stroke
				(width 0.1)
				(type default)
			)
			(layer "F.Fab")
		)
		(fp_line
			(start 0.120396 0.2794)
			(end -0.12065 0.2794)
			(stroke
				(width 0.1)
				(type default)
			)
			(layer "F.Fab")
		)
		(fp_line
			(start -0.12065 0.3048)
			(end -0.67945 0.3048)
			(stroke
				(width 0.1)
				(type default)
			)
			(layer "F.Fab")
		)
		(fp_line
			(start -0.12065 0.2794)
			(end -0.12065 0.3048)
			(stroke
				(width 0.1)
				(type default)
			)
			(layer "F.Fab")
		)
		(fp_line
			(start -0.12065 -0.2794)
			(end 0.12065 -0.2794)
			(stroke
				(width 0.1)
				(type default)
			)
			(layer "F.Fab")
		)
		(fp_line
			(start -0.12065 -0.305054)
			(end -0.12065 -0.2794)
			(stroke
				(width 0.1)
				(type default)
			)
			(layer "F.Fab")
		)
		(fp_line
			(start -0.67945 0.3048)
			(end -0.67945 -0.305054)
			(stroke
				(width 0.1)
				(type default)
			)
			(layer "F.Fab")
		)
		(fp_line
			(start -0.67945 -0.305054)
			(end -0.12065 -0.305054)
			(stroke
				(width 0.1)
				(type default)
			)
			(layer "F.Fab")
		)
		(pad "1" smd circle
			(at -0.40005 0 180)
			(size 0 0)
			(layers "F.Cu" "F.Mask" "F.Paste")
			(net "SMB_SML0B_3V3AUX_SCL")
		)
		(pad "2" smd circle
			(at 0.40005 0 180)
			(size 0 0)
			(layers "F.Cu" "F.Mask" "F.Paste")
			(net "P3V3_AUX")
		)
	)
	(footprint ""
		(layer "F.Cu")
		(at 164.64788 -112.232948)
		(property "Reference" "R3477"
			(at 0 0 0)
			(layer "F.SilkS")
			(hide yes)
			(effects
				(font
					(size 1.27 1.27)
				)
			)
		)
		(property "Value" ""
			(at 0 0 0)
			(layer "F.Fab")
			(effects
				(font
					(size 1.27 1.27)
				)
			)
		)
		(duplicate_pad_numbers_are_jumpers no)
		(fp_line
			(start -0.7874 -0.4064)
			(end 0.7874 -0.4064)
			(stroke
				(width 0.1524)
				(type default)
			)
			(layer "F.SilkS")
		)
		(fp_line
			(start -0.7874 0.4064)
			(end -0.7874 -0.4064)
			(stroke
				(width 0.1524)
				(type default)
			)
			(layer "F.SilkS")
		)
		(fp_line
			(start 0.7874 -0.4064)
			(end 0.7874 0.4064)
			(stroke
				(width 0.1524)
				(type default)
			)
			(layer "F.SilkS")
		)
		(fp_line
			(start 0.7874 0.4064)
			(end -0.7874 0.4064)
			(stroke
				(width 0.1524)
				(type default)
			)
			(layer "F.SilkS")
		)
		(fp_line
			(start -0.67945 -0.305054)
			(end -0.12065 -0.305054)
			(stroke
				(width 0.1)
				(type default)
			)
			(layer "F.Fab")
		)
		(fp_line
			(start -0.67945 0.3048)
			(end -0.67945 -0.305054)
			(stroke
				(width 0.1)
				(type default)
			)
			(layer "F.Fab")
		)
		(fp_line
			(start -0.12065 -0.305054)
			(end -0.12065 -0.2794)
			(stroke
				(width 0.1)
				(type default)
			)
			(layer "F.Fab")
		)
		(fp_line
			(start -0.12065 -0.2794)
			(end 0.12065 -0.2794)
			(stroke
				(width 0.1)
				(type default)
			)
			(layer "F.Fab")
		)
		(fp_line
			(start -0.12065 0.2794)
			(end -0.12065 0.3048)
			(stroke
				(width 0.1)
				(type default)
			)
			(layer "F.Fab")
		)
		(fp_line
			(start -0.12065 0.3048)
			(end -0.67945 0.3048)
			(stroke
				(width 0.1)
				(type default)
			)
			(layer "F.Fab")
		)
		(fp_line
			(start 0.120396 0.2794)
			(end -0.12065 0.2794)
			(stroke
				(width 0.1)
				(type default)
			)
			(layer "F.Fab")
		)
		(fp_line
			(start 0.120396 0.3048)
			(end 0.120396 0.2794)
			(stroke
				(width 0.1)
				(type default)
			)
			(layer "F.Fab")
		)
		(fp_line
			(start 0.12065 -0.3048)
			(end 0.67945 -0.3048)
			(stroke
				(width 0.1)
				(type default)
			)
			(layer "F.Fab")
		)
		(fp_line
			(start 0.12065 -0.2794)
			(end 0.12065 -0.3048)
			(stroke
				(width 0.1)
				(type default)
			)
			(layer "F.Fab")
		)
		(fp_line
			(start 0.67945 -0.3048)
			(end 0.67945 0.3048)
			(stroke
				(width 0.1)
				(type default)
			)
			(layer "F.Fab")
		)
		(fp_line
			(start 0.67945 0.3048)
			(end 0.120396 0.3048)
			(stroke
				(width 0.1)
				(type default)
			)
			(layer "F.Fab")
		)
		(pad "1" smd circle
			(at -0.40005 0)
			(size 0 0)
			(layers "F.Cu" "F.Mask" "F.Paste")
			(net "GPU_NVS_PWR_BRAKE_N")
		)
		(pad "2" smd circle
			(at 0.40005 0)
			(size 0 0)
			(layers "F.Cu" "F.Mask" "F.Paste")
			(net "GPU_NVS_PWR_BRAKE_R_N")
		)
	)
	(footprint ""
		(layer "F.Cu")
		(at 323.680328 -408.517344 -90)
		(property "Reference" "C914"
			(at 0 0 270)
			(layer "F.SilkS")
			(hide yes)
			(effects
				(font
					(size 1.27 1.27)
				)
			)
		)
		(property "Value" ""
			(at 0 0 270)
			(layer "F.Fab")
			(effects
				(font
					(size 1.27 1.27)
				)
			)
		)
		(duplicate_pad_numbers_are_jumpers no)
		(fp_line
			(start -0.299974 0.150114)
			(end -0.299974 -0.150114)
			(stroke
				(width 0.1)
				(type default)
			)
			(layer "F.Fab")
		)
		(fp_line
			(start 0.299974 0.150114)
			(end -0.299974 0.150114)
			(stroke
				(width 0.1)
				(type default)
			)
			(layer "F.Fab")
		)
		(fp_line
			(start -0.299974 -0.150114)
			(end 0.299974 -0.150114)
			(stroke
				(width 0.1)
				(type default)
			)
			(layer "F.Fab")
		)
		(fp_line
			(start 0.299974 -0.150114)
			(end 0.299974 0.150114)
			(stroke
				(width 0.1)
				(type default)
			)
			(layer "F.Fab")
		)
		(pad "1" smd rect
			(at -0.2667 0 270)
			(size 0.3048 0.381)
			(layers "F.Cu" "F.Mask" "F.Paste")
			(net "P5E_CPU0_PE0_TX_C_DN<9>")
		)
		(pad "2" smd rect
			(at 0.2667 0 270)
			(size 0.3048 0.381)
			(layers "F.Cu" "F.Mask" "F.Paste")
			(net "P5E_CPU0_PE0_TX_DN<9>")
		)
	)
)
